(kicad_pcb
	(version 20260206)
	(generator "pcbnew")
	(generator_version "10.0")
	(general
		(thickness 1.6)
		(legacy_teardrops no)
	)
	(paper "A4")
	(title_block
		(title "pdpb — Lightning_PDPB_BRD.brd")
		(comment 1 "Lightning (Wiwynn / Facebook NVMe JBOF) / footprints 677-683 of 1140")
	)
	(layers
		(0 "F.Cu" signal "TOP")
		(4 "In1.Cu" signal "L2GND")
		(6 "In2.Cu" signal "L3")
		(8 "In3.Cu" signal "L4VCC")
		(10 "In4.Cu" signal "L5VCC")
		(12 "In5.Cu" signal "L6")
		(14 "In6.Cu" signal "L7GND")
		(2 "B.Cu" signal "BOTTOM")
		(9 "F.Adhes" user "F.Adhesive")
		(11 "B.Adhes" user "B.Adhesive")
		(13 "F.Paste" user "Package Geometry/Pastemask Top")
		(15 "B.Paste" user "Package Geometry/Pastemask Bottom")
		(5 "F.SilkS" user "Ref Des/Silkscreen Top")
		(7 "B.SilkS" user "Ref Des/Silkscreen Bottom")
		(1 "F.Mask" user "Board Geometry/Soldermask Top")
		(3 "B.Mask" user "Board Geometry/Soldermask Bottom")
		(17 "Dwgs.User" user "User.Drawings")
		(19 "Cmts.User" user "User.Comments")
		(21 "Eco1.User" user "User.Eco1")
		(23 "Eco2.User" user "User.Eco2")
		(25 "Edge.Cuts" user "Board Geometry/Outline")
		(27 "Margin" user)
		(31 "F.CrtYd" user "Package Geometry/Place Bound Top")
		(29 "B.CrtYd" user "Package Geometry/Place Bound Bottom")
		(35 "F.Fab" user "Ref Des/Assembly Top")
		(33 "B.Fab" user "Ref Des/Assembly Bottom")
	)
	(footprint ""
		(layer "F.Cu")
		(at 79.121 -354.076)
		(property "Reference" "SR1156"
			(at 0 0 0)
			(layer "F.SilkS")
			(hide yes)
			(effects
				(font
					(size 1.27 1.27)
				)
			)
		)
		(property "Value" "4K7R2F-GP"
			(at 0.064008 -3.993896 0)
			(unlocked yes)
			(layer "F.Fab")
			(hide yes)
			(effects
				(font
					(size 1.016 1.016)
					(thickness 0.1524)
				)
			)
		)
		(property "Device Type" "R402H16"
			(at 0.064008 -5.517896 0)
			(unlocked yes)
			(layer "F.Fab")
			(hide yes)
			(effects
				(font
					(size 1.016 1.016)
					(thickness 0.1524)
				)
			)
		)
		(duplicate_pad_numbers_are_jumpers no)
		(fp_line
			(start -0.508 -0.9398)
			(end -0.508 0.9398)
			(stroke
				(width 0.1524)
				(type default)
			)
			(layer "F.SilkS")
		)
		(fp_line
			(start 0.508 -0.9398)
			(end -0.508 -0.9398)
			(stroke
				(width 0.1524)
				(type default)
			)
			(layer "F.SilkS")
		)
		(fp_rect
			(start -0.508 0.9398)
			(end 0.508 -0.9398)
			(stroke
				(width 0)
				(type default)
			)
			(fill no)
			(layer "F.CrtYd")
		)
		(fp_rect
			(start -0.508 0.9398)
			(end 0.508 -0.9398)
			(stroke
				(width 0)
				(type default)
			)
			(fill no)
			(layer "F.Fab")
		)
		(pad "1" smd custom
			(at 0 -0.4445)
			(size 0.1397 0.1397)
			(layers "F.Cu" "F.Mask" "F.Paste")
			(net "I2C_SW_EU17_ADDRESS_A1")
			(options
				(clearance outline)
				(anchor circle)
			)
			(primitives
				(gr_poly
					(pts
						(arc
							(start -0.1778 -0.2794)
							(mid -0.249642 -0.249642)
							(end -0.2794 -0.1778)
						)
						(arc
							(start -0.2794 0.1778)
							(mid -0.249642 0.249642)
							(end -0.1778 0.2794)
						)
						(arc
							(start 0.1778 0.2794)
							(mid 0.249642 0.249642)
							(end 0.2794 0.1778)
						)
						(arc
							(start 0.2794 -0.1778)
							(mid 0.249642 -0.249642)
							(end 0.1778 -0.2794)
						)
					)
					(width 0)
					(fill yes)
				)
			)
		)
		(pad "2" smd custom
			(at 0 0.4445)
			(size 0.1397 0.1397)
			(layers "F.Cu" "F.Mask" "F.Paste")
			(net "GND")
			(options
				(clearance outline)
				(anchor circle)
			)
			(primitives
				(gr_poly
					(pts
						(arc
							(start -0.1778 -0.2794)
							(mid -0.249642 -0.249642)
							(end -0.2794 -0.1778)
						)
						(arc
							(start -0.2794 0.1778)
							(mid -0.249642 0.249642)
							(end -0.1778 0.2794)
						)
						(arc
							(start 0.1778 0.2794)
							(mid 0.249642 0.249642)
							(end 0.2794 0.1778)
						)
						(arc
							(start 0.2794 -0.1778)
							(mid 0.249642 -0.249642)
							(end 0.1778 -0.2794)
						)
					)
					(width 0)
					(fill yes)
				)
			)
		)
	)
	(footprint ""
		(layer "F.Cu")
		(at 84.455 -425.958 90)
		(property "Reference" "PR9008"
			(at 0 0 90)
			(layer "F.SilkS")
			(hide yes)
			(effects
				(font
					(size 1.27 1.27)
				)
			)
		)
		(property "Value" "4K7R2F-GP"
			(at 0.064008 -3.993896 90)
			(unlocked yes)
			(layer "F.Fab")
			(hide yes)
			(effects
				(font
					(size 1.016 1.016)
					(thickness 0.1524)
				)
			)
		)
		(property "Device Type" "R402H16"
			(at 0.064008 -5.517896 90)
			(unlocked yes)
			(layer "F.Fab")
			(hide yes)
			(effects
				(font
					(size 1.016 1.016)
					(thickness 0.1524)
				)
			)
		)
		(duplicate_pad_numbers_are_jumpers no)
		(fp_line
			(start 0.508 -0.9398)
			(end -0.508 -0.9398)
			(stroke
				(width 0.1524)
				(type default)
			)
			(layer "F.SilkS")
		)
		(fp_line
			(start -0.508 -0.9398)
			(end -0.508 0.9398)
			(stroke
				(width 0.1524)
				(type default)
			)
			(layer "F.SilkS")
		)
		(fp_rect
			(start -0.508 0.9398)
			(end 0.508 -0.9398)
			(stroke
				(width 0)
				(type default)
			)
			(fill no)
			(layer "F.CrtYd")
		)
		(fp_rect
			(start -0.508 0.9398)
			(end 0.508 -0.9398)
			(stroke
				(width 0)
				(type default)
			)
			(fill no)
			(layer "F.Fab")
		)
		(pad "1" smd custom
			(at 0 -0.4445 90)
			(size 0.1397 0.1397)
			(layers "F.Cu" "F.Mask" "F.Paste")
			(net "VDD_DIFF_1")
			(options
				(clearance outline)
				(anchor circle)
			)
			(primitives
				(gr_poly
					(pts
						(arc
							(start -0.1778 -0.2794)
							(mid -0.249642 -0.249642)
							(end -0.2794 -0.1778)
						)
						(arc
							(start -0.2794 0.1778)
							(mid -0.249642 0.249642)
							(end -0.1778 0.2794)
						)
						(arc
							(start 0.1778 0.2794)
							(mid 0.249642 0.249642)
							(end 0.2794 0.1778)
						)
						(arc
							(start 0.2794 -0.1778)
							(mid 0.249642 -0.249642)
							(end 0.1778 -0.2794)
						)
					)
					(width 0)
					(fill yes)
				)
			)
		)
		(pad "2" smd custom
			(at 0 0.4445 90)
			(size 0.1397 0.1397)
			(layers "F.Cu" "F.Mask" "F.Paste")
			(net "CLK_BUF_EU1_SMB_A1_TRI")
			(options
				(clearance outline)
				(anchor circle)
			)
			(primitives
				(gr_poly
					(pts
						(arc
							(start -0.1778 -0.2794)
							(mid -0.249642 -0.249642)
							(end -0.2794 -0.1778)
						)
						(arc
							(start -0.2794 0.1778)
							(mid -0.249642 0.249642)
							(end -0.1778 0.2794)
						)
						(arc
							(start 0.1778 0.2794)
							(mid 0.249642 0.249642)
							(end 0.2794 0.1778)
						)
						(arc
							(start 0.2794 -0.1778)
							(mid 0.249642 -0.249642)
							(end 0.1778 -0.2794)
						)
					)
					(width 0)
					(fill yes)
				)
			)
		)
	)
	(footprint ""
		(layer "F.Cu")
		(at 52.66055 -6.02615 -90)
		(property "Reference" "R9871"
			(at 0 0 270)
			(layer "F.SilkS")
			(hide yes)
			(effects
				(font
					(size 1.27 1.27)
				)
			)
		)
		(property "Value" "1KR2J-1-GP"
			(at 0.064008 -3.993896 270)
			(unlocked yes)
			(layer "F.Fab")
			(hide yes)
			(effects
				(font
					(size 1.016 1.016)
					(thickness 0.1524)
				)
			)
		)
		(property "Device Type" "R402H16"
			(at 0.064008 -5.517896 270)
			(unlocked yes)
			(layer "F.Fab")
			(hide yes)
			(effects
				(font
					(size 1.016 1.016)
					(thickness 0.1524)
				)
			)
		)
		(duplicate_pad_numbers_are_jumpers no)
		(fp_line
			(start -0.508 -0.9398)
			(end -0.508 0.9398)
			(stroke
				(width 0.1524)
				(type default)
			)
			(layer "F.SilkS")
		)
		(fp_line
			(start 0.508 -0.9398)
			(end -0.508 -0.9398)
			(stroke
				(width 0.1524)
				(type default)
			)
			(layer "F.SilkS")
		)
		(fp_rect
			(start -0.508 0.9398)
			(end 0.508 -0.9398)
			(stroke
				(width 0)
				(type default)
			)
			(fill no)
			(layer "F.CrtYd")
		)
		(fp_rect
			(start -0.508 0.9398)
			(end 0.508 -0.9398)
			(stroke
				(width 0)
				(type default)
			)
			(fill no)
			(layer "F.Fab")
		)
		(pad "1" smd custom
			(at 0 -0.4445 270)
			(size 0.1397 0.1397)
			(layers "F.Cu" "F.Mask" "F.Paste")
			(net "SSD14_PWREN")
			(options
				(clearance outline)
				(anchor circle)
			)
			(primitives
				(gr_poly
					(pts
						(arc
							(start -0.1778 -0.2794)
							(mid -0.249642 -0.249642)
							(end -0.2794 -0.1778)
						)
						(arc
							(start -0.2794 0.1778)
							(mid -0.249642 0.249642)
							(end -0.1778 0.2794)
						)
						(arc
							(start 0.1778 0.2794)
							(mid 0.249642 0.249642)
							(end 0.2794 0.1778)
						)
						(arc
							(start 0.2794 -0.1778)
							(mid 0.249642 -0.249642)
							(end 0.1778 -0.2794)
						)
					)
					(width 0)
					(fill yes)
				)
			)
		)
		(pad "2" smd custom
			(at 0 0.4445 270)
			(size 0.1397 0.1397)
			(layers "F.Cu" "F.Mask" "F.Paste")
			(net "SSD14_PWREN_R")
			(options
				(clearance outline)
				(anchor circle)
			)
			(primitives
				(gr_poly
					(pts
						(arc
							(start -0.1778 -0.2794)
							(mid -0.249642 -0.249642)
							(end -0.2794 -0.1778)
						)
						(arc
							(start -0.2794 0.1778)
							(mid -0.249642 0.249642)
							(end -0.1778 0.2794)
						)
						(arc
							(start 0.1778 0.2794)
							(mid 0.249642 0.249642)
							(end 0.2794 0.1778)
						)
						(arc
							(start 0.2794 -0.1778)
							(mid 0.249642 -0.249642)
							(end 0.1778 -0.2794)
						)
					)
					(width 0)
					(fill yes)
				)
			)
		)
	)
	(footprint ""
		(layer "F.Cu")
		(at 72.136 -154.178)
		(property "Reference" "SR973"
			(at 0 0 0)
			(layer "F.SilkS")
			(hide yes)
			(effects
				(font
					(size 1.27 1.27)
				)
			)
		)
		(property "Value" "2KR2F-3-GP"
			(at 0.064008 -3.993896 0)
			(unlocked yes)
			(layer "F.Fab")
			(hide yes)
			(effects
				(font
					(size 1.016 1.016)
					(thickness 0.1524)
				)
			)
		)
		(property "Device Type" "R402H16"
			(at 0.064008 -5.517896 0)
			(unlocked yes)
			(layer "F.Fab")
			(hide yes)
			(effects
				(font
					(size 1.016 1.016)
					(thickness 0.1524)
				)
			)
		)
		(duplicate_pad_numbers_are_jumpers no)
		(fp_line
			(start -0.508 -0.9398)
			(end -0.508 0.9398)
			(stroke
				(width 0.1524)
				(type default)
			)
			(layer "F.SilkS")
		)
		(fp_line
			(start 0.508 -0.9398)
			(end -0.508 -0.9398)
			(stroke
				(width 0.1524)
				(type default)
			)
			(layer "F.SilkS")
		)
		(fp_rect
			(start -0.508 0.9398)
			(end 0.508 -0.9398)
			(stroke
				(width 0)
				(type default)
			)
			(fill no)
			(layer "F.CrtYd")
		)
		(fp_rect
			(start -0.508 0.9398)
			(end 0.508 -0.9398)
			(stroke
				(width 0)
				(type default)
			)
			(fill no)
			(layer "F.Fab")
		)
		(pad "1" smd custom
			(at 0 -0.4445)
			(size 0.1397 0.1397)
			(layers "F.Cu" "F.Mask" "F.Paste")
			(net "P3V3")
			(options
				(clearance outline)
				(anchor circle)
			)
			(primitives
				(gr_poly
					(pts
						(arc
							(start -0.1778 -0.2794)
							(mid -0.249642 -0.249642)
							(end -0.2794 -0.1778)
						)
						(arc
							(start -0.2794 0.1778)
							(mid -0.249642 0.249642)
							(end -0.1778 0.2794)
						)
						(arc
							(start 0.1778 0.2794)
							(mid 0.249642 0.249642)
							(end 0.2794 0.1778)
						)
						(arc
							(start 0.2794 -0.1778)
							(mid 0.249642 -0.249642)
							(end 0.1778 -0.2794)
						)
					)
					(width 0)
					(fill yes)
				)
			)
		)
		(pad "2" smd custom
			(at 0 0.4445)
			(size 0.1397 0.1397)
			(layers "F.Cu" "F.Mask" "F.Paste")
			(net "SCL_DR12")
			(options
				(clearance outline)
				(anchor circle)
			)
			(primitives
				(gr_poly
					(pts
						(arc
							(start -0.1778 -0.2794)
							(mid -0.249642 -0.249642)
							(end -0.2794 -0.1778)
						)
						(arc
							(start -0.2794 0.1778)
							(mid -0.249642 0.249642)
							(end -0.1778 0.2794)
						)
						(arc
							(start 0.1778 0.2794)
							(mid 0.249642 0.249642)
							(end 0.2794 0.1778)
						)
						(arc
							(start 0.2794 -0.1778)
							(mid 0.249642 -0.249642)
							(end 0.1778 -0.2794)
						)
					)
					(width 0)
					(fill yes)
				)
			)
		)
	)
	(footprint ""
		(layer "F.Cu")
		(at 43.999912 -137.999978 -90)
		(property "Reference" "U51"
			(at 0 0 270)
			(layer "F.SilkS")
			(hide yes)
			(effects
				(font
					(size 1.27 1.27)
				)
			)
		)
		(property "Value" "TMP75AIDGKR-GP"
			(at -0.1143 -9.1948 270)
			(unlocked yes)
			(layer "F.Fab")
			(hide yes)
			(effects
				(font
					(size 1.016 1.016)
					(thickness 0.1524)
				)
			)
		)
		(property "Device Type" "MSOP8-1H44"
			(at -0.1143 -10.795 270)
			(unlocked yes)
			(layer "F.Fab")
			(hide yes)
			(effects
				(font
					(size 1.016 1.016)
					(thickness 0.1524)
				)
			)
		)
		(duplicate_pad_numbers_are_jumpers no)
		(fp_line
			(start -1.778 1.0922)
			(end -1.778 3.048)
			(stroke
				(width 0.508)
				(type default)
			)
			(layer "F.SilkS")
		)
		(fp_line
			(start -1.9558 1.016)
			(end 1.0795 1.016)
			(stroke
				(width 0.1524)
				(type default)
			)
			(layer "F.SilkS")
		)
		(fp_line
			(start 1.0795 1.016)
			(end 1.0795 -1.016)
			(stroke
				(width 0.1524)
				(type default)
			)
			(layer "F.SilkS")
		)
		(fp_line
			(start -1.4478 -0.0381)
			(end -1.9558 0.4699)
			(stroke
				(width 0.1524)
				(type default)
			)
			(layer "F.SilkS")
		)
		(fp_line
			(start -1.9558 -0.5461)
			(end -1.4478 -0.0381)
			(stroke
				(width 0.1524)
				(type default)
			)
			(layer "F.SilkS")
		)
		(fp_line
			(start -1.9558 -1.016)
			(end -1.9558 1.016)
			(stroke
				(width 0.1524)
				(type default)
			)
			(layer "F.SilkS")
		)
		(fp_line
			(start 1.0795 -1.016)
			(end -1.9558 -1.016)
			(stroke
				(width 0.1524)
				(type default)
			)
			(layer "F.SilkS")
		)
		(fp_poly
			(pts
				(xy -1.1557 -1.016) (xy -1.1557 1.016) (xy 1.1557 1.016) (xy 1.1557 -1.016)
			)
			(stroke
				(width 0)
				(type default)
			)
			(fill yes)
			(layer "F.SilkS")
		)
		(fp_rect
			(start -1.4986 2.4511)
			(end 1.4986 -2.4511)
			(stroke
				(width 0)
				(type default)
			)
			(fill no)
			(layer "F.CrtYd")
		)
		(fp_poly
			(pts
				(xy -2.032 3.302) (xy -2.032 -3.302) (xy 2.032 -3.302) (xy 2.032 -2.1209) (xy 1.4986 -2.1209) (xy 1.4986 -2.4511)
				(xy -1.4986 -2.4511) (xy -1.4986 2.4511) (xy 1.4986 2.4511) (xy 1.4986 -2.1082) (xy 2.032 -2.1082)
				(xy 2.032 3.302)
			)
			(stroke
				(width 0)
				(type default)
			)
			(fill no)
			(layer "F.CrtYd")
		)
		(fp_rect
			(start -2.032 3.302)
			(end 2.032 -3.302)
			(stroke
				(width 0)
				(type default)
			)
			(fill no)
			(layer "F.Fab")
		)
		(pad "1" smd rect
			(at -0.97536 2.05486 270)
			(size 0.3556 1.524)
			(layers "F.Cu" "F.Mask" "F.Paste")
			(net "TMP1_SDA")
		)
		(pad "2" smd rect
			(at -0.32512 2.05486 270)
			(size 0.3556 1.524)
			(layers "F.Cu" "F.Mask" "F.Paste")
			(net "TMP1_SCL")
		)
		(pad "3" smd rect
			(at 0.32512 2.05486 270)
			(size 0.3556 1.524)
			(layers "F.Cu" "F.Mask" "F.Paste")
			(net "I2C_B_TMP1_ALERT")
		)
		(pad "4" smd rect
			(at 0.97536 2.05486 270)
			(size 0.3556 1.524)
			(layers "F.Cu" "F.Mask" "F.Paste")
			(net "GND")
		)
		(pad "5" smd rect
			(at 0.97536 -2.05486 270)
			(size 0.3556 1.524)
			(layers "F.Cu" "F.Mask" "F.Paste")
			(net "I2C_B_TMP1_A2")
		)
		(pad "6" smd rect
			(at 0.32512 -2.05486 270)
			(size 0.3556 1.524)
			(layers "F.Cu" "F.Mask" "F.Paste")
			(net "I2C_B_TMP1_A1")
		)
		(pad "7" smd rect
			(at -0.32512 -2.05486 270)
			(size 0.3556 1.524)
			(layers "F.Cu" "F.Mask" "F.Paste")
			(net "I2C_B_TMP1_A0")
		)
		(pad "8" smd rect
			(at -0.97536 -2.05486 270)
			(size 0.3556 1.524)
			(layers "F.Cu" "F.Mask" "F.Paste")
			(net "P3V3")
		)
	)
	(footprint ""
		(layer "F.Cu")
		(at 70.739 -361.569 90)
		(property "Reference" "SR981"
			(at 0 0 90)
			(layer "F.SilkS")
			(hide yes)
			(effects
				(font
					(size 1.27 1.27)
				)
			)
		)
		(property "Value" "2KR2F-3-GP"
			(at 0.064008 -3.993896 90)
			(unlocked yes)
			(layer "F.Fab")
			(hide yes)
			(effects
				(font
					(size 1.016 1.016)
					(thickness 0.1524)
				)
			)
		)
		(property "Device Type" "R402H16"
			(at 0.064008 -5.517896 90)
			(unlocked yes)
			(layer "F.Fab")
			(hide yes)
			(effects
				(font
					(size 1.016 1.016)
					(thickness 0.1524)
				)
			)
		)
		(duplicate_pad_numbers_are_jumpers no)
		(fp_line
			(start 0.508 -0.9398)
			(end -0.508 -0.9398)
			(stroke
				(width 0.1524)
				(type default)
			)
			(layer "F.SilkS")
		)
		(fp_line
			(start -0.508 -0.9398)
			(end -0.508 0.9398)
			(stroke
				(width 0.1524)
				(type default)
			)
			(layer "F.SilkS")
		)
		(fp_rect
			(start -0.508 0.9398)
			(end 0.508 -0.9398)
			(stroke
				(width 0)
				(type default)
			)
			(fill no)
			(layer "F.CrtYd")
		)
		(fp_rect
			(start -0.508 0.9398)
			(end 0.508 -0.9398)
			(stroke
				(width 0)
				(type default)
			)
			(fill no)
			(layer "F.Fab")
		)
		(pad "1" smd custom
			(at 0 -0.4445 90)
			(size 0.1397 0.1397)
			(layers "F.Cu" "F.Mask" "F.Paste")
			(net "P3V3")
			(options
				(clearance outline)
				(anchor circle)
			)
			(primitives
				(gr_poly
					(pts
						(arc
							(start -0.1778 -0.2794)
							(mid -0.249642 -0.249642)
							(end -0.2794 -0.1778)
						)
						(arc
							(start -0.2794 0.1778)
							(mid -0.249642 0.249642)
							(end -0.1778 0.2794)
						)
						(arc
							(start 0.1778 0.2794)
							(mid 0.249642 0.249642)
							(end 0.2794 0.1778)
						)
						(arc
							(start 0.2794 -0.1778)
							(mid 0.249642 -0.249642)
							(end 0.1778 -0.2794)
						)
					)
					(width 0)
					(fill yes)
				)
			)
		)
		(pad "2" smd custom
			(at 0 0.4445 90)
			(size 0.1397 0.1397)
			(layers "F.Cu" "F.Mask" "F.Paste")
			(net "SCL_DR11")
			(options
				(clearance outline)
				(anchor circle)
			)
			(primitives
				(gr_poly
					(pts
						(arc
							(start -0.1778 -0.2794)
							(mid -0.249642 -0.249642)
							(end -0.2794 -0.1778)
						)
						(arc
							(start -0.2794 0.1778)
							(mid -0.249642 0.249642)
							(end -0.1778 0.2794)
						)
						(arc
							(start 0.1778 0.2794)
							(mid 0.249642 0.249642)
							(end 0.2794 0.1778)
						)
						(arc
							(start 0.2794 -0.1778)
							(mid 0.249642 -0.249642)
							(end 0.1778 -0.2794)
						)
					)
					(width 0)
					(fill yes)
				)
			)
		)
	)
	(footprint ""
		(layer "F.Cu")
		(at 49.022 -14.859 180)
		(property "Reference" "C396"
			(at 0 0 180)
			(layer "F.SilkS")
			(hide yes)
			(effects
				(font
					(size 1.27 1.27)
				)
			)
		)
		(property "Value" "SCD1U25V2KX-2-GP"
			(at 1.1811 -2.7051 180)
			(unlocked yes)
			(layer "F.Fab")
			(hide yes)
			(effects
				(font
					(size 1.016 1.016)
					(thickness 0.1524)
				)
			)
		)
		(property "Device Type" "C402H22"
			(at 1.1811 -4.2291 180)
			(unlocked yes)
			(layer "F.Fab")
			(hide yes)
			(effects
				(font
					(size 1.016 1.016)
					(thickness 0.1524)
				)
			)
		)
		(duplicate_pad_numbers_are_jumpers no)
		(fp_rect
			(start -0.4318 0.9525)
			(end 0.4318 -0.9525)
			(stroke
				(width 0)
				(type default)
			)
			(fill no)
			(layer "F.CrtYd")
		)
		(fp_rect
			(start -0.4318 0.9525)
			(end 0.4318 -0.9525)
			(stroke
				(width 0)
				(type default)
			)
			(fill no)
			(layer "F.Fab")
		)
		(pad "1" smd custom
			(at 0 -0.4445 180)
			(size 0.1524 0.1524)
			(layers "F.Cu" "F.Mask" "F.Paste")
			(net "P12V")
			(options
				(clearance outline)
				(anchor circle)
			)
			(primitives
				(gr_poly
					(pts
						(arc
							(start 0.3048 -0.2032)
							(mid 0.275042 -0.275042)
							(end 0.2032 -0.3048)
						)
						(arc
							(start -0.2032 -0.3048)
							(mid -0.275042 -0.275042)
							(end -0.3048 -0.2032)
						)
						(arc
							(start -0.3048 0.2032)
							(mid -0.275042 0.275042)
							(end -0.2032 0.3048)
						)
						(arc
							(start 0.2032 0.3048)
							(mid 0.275042 0.275042)
							(end 0.3048 0.2032)
						)
					)
					(width 0)
					(fill yes)
				)
			)
		)
		(pad "2" smd custom
			(at 0 0.4445 180)
			(size 0.1524 0.1524)
			(layers "F.Cu" "F.Mask" "F.Paste")
			(net "SW_SSD14_N")
			(options
				(clearance outline)
				(anchor circle)
			)
			(primitives
				(gr_poly
					(pts
						(arc
							(start 0.3048 -0.2032)
							(mid 0.275042 -0.275042)
							(end 0.2032 -0.3048)
						)
						(arc
							(start -0.2032 -0.3048)
							(mid -0.275042 -0.275042)
							(end -0.3048 -0.2032)
						)
						(arc
							(start -0.3048 0.2032)
							(mid -0.275042 0.275042)
							(end -0.2032 0.3048)
						)
						(arc
							(start 0.2032 0.3048)
							(mid 0.275042 0.275042)
							(end 0.3048 0.2032)
						)
					)
					(width 0)
					(fill yes)
				)
			)
		)
	)
)
